(kicad_pcb
	(version 20260206)
	(generator "pcbnew")
	(generator_version "10.0")
	(general
		(thickness 1.6)
		(legacy_teardrops no)
	)
	(paper "A4")
	(title_block
		(title "04192023_DAF0TMB3IC0_F0TG_MB_C_brd_V02_OCP.brd")
		(comment 1 "Grand Teton / footprint 4346 of 8354 (U6010), pads 224-336 of 354")
	)
	(layers
		(0 "F.Cu" signal "TOP")
		(4 "In1.Cu" signal "GND")
		(6 "In2.Cu" signal "IN1")
		(8 "In3.Cu" signal "GND1")
		(10 "In4.Cu" signal "IN2")
		(12 "In5.Cu" signal "GND2")
		(14 "In6.Cu" signal "IN3")
		(16 "In7.Cu" signal "GND3")
		(18 "In8.Cu" signal "VCC")
		(20 "In9.Cu" signal "VCC1")
		(22 "In10.Cu" signal "GND4")
		(24 "In11.Cu" signal "IN4")
		(26 "In12.Cu" signal "GND5")
		(28 "In13.Cu" signal "IN5")
		(30 "In14.Cu" signal "GND6")
		(32 "In15.Cu" signal "IN6")
		(34 "In16.Cu" signal "GND7")
		(2 "B.Cu" signal "BOTTOM")
		(9 "F.Adhes" user "F.Adhesive")
		(11 "B.Adhes" user "B.Adhesive")
		(13 "F.Paste" user "Package Geometry/Pastemask Top")
		(15 "B.Paste" user "Package Geometry/Pastemask Bottom")
		(5 "F.SilkS" user "Ref Des/Silkscreen Top")
		(7 "B.SilkS" user "Ref Des/Silkscreen Bottom")
		(1 "F.Mask" user "Board Geometry/Soldermask Top")
		(3 "B.Mask" user "Board Geometry/Soldermask Bottom")
		(17 "Dwgs.User" user "User.Drawings")
		(19 "Cmts.User" user "User.Comments")
		(21 "Eco1.User" user "User.Eco1")
		(23 "Eco2.User" user "User.Eco2")
		(25 "Edge.Cuts" user "Board Geometry/Outline")
		(27 "Margin" user)
		(31 "F.CrtYd" user "Package Geometry/Place Bound Top")
		(29 "B.CrtYd" user "Package Geometry/Place Bound Bottom")
		(35 "F.Fab" user "Ref Des/Assembly Top")
		(33 "B.Fab" user "Ref Des/Assembly Bottom")
	)
	(footprint ""
		(layer "F.Cu")
		(at 312.467752 -395.724634)
		(property "Reference" "U6010"
			(at -6.426454 -7.380224 0)
			(unlocked yes)
			(layer "F.SilkS")
			(effects
				(font
					(size 0.7874 0.5842)
					(thickness 0.1524)
				)
				(justify left)
			)
		)
		(property "Value" ""
			(at 0 0 0)
			(layer "F.Fab")
			(effects
				(font
					(size 1.27 1.27)
				)
			)
		)
		(duplicate_pad_numbers_are_jumpers no)
		(pad "DY32" smd circle
			(at -5.997448 2.724912)
			(size 0.381 0.381)
			(layers "F.Cu" "F.Mask" "F.Paste")
			(net "GND")
		)
		(pad "E8" smd circle
			(at 10.366502 -1.988312)
			(size 0.3048 0.3048)
			(layers "F.Cu" "F.Mask" "F.Paste")
			(net "JTAG_TRST_RT_CPU0_P0_N")
		)
		(pad "E11" smd circle
			(at 10.366502 -1.388364)
			(size 0.3048 0.3048)
			(layers "F.Cu" "F.Mask" "F.Paste")
			(net "RXDET_BYP_RT_CPU0_P0")
		)
		(pad "E14" smd circle
			(at 10.366502 -0.788416)
			(size 0.3048 0.3048)
			(layers "F.Cu" "F.Mask" "F.Paste")
			(net "GND")
		)
		(pad "E18" smd circle
			(at 10.366502 -0.188468)
			(size 0.3048 0.3048)
			(layers "F.Cu" "F.Mask" "F.Paste")
			(net "Net_2202")
		)
		(pad "E27" smd circle
			(at 10.366502 1.61163)
			(size 0.3048 0.3048)
			(layers "F.Cu" "F.Mask" "F.Paste")
			(net "GND")
		)
		(pad "E30" smd circle
			(at 10.366502 2.211578)
			(size 0.3048 0.3048)
			(layers "F.Cu" "F.Mask" "F.Paste")
			(net "GND")
		)
		(pad "E33" smd circle
			(at 10.366502 2.811526)
			(size 0.3048 0.3048)
			(layers "F.Cu" "F.Mask" "F.Paste")
			(net "GND")
		)
		(pad "EA2" smd circle
			(at -6.050026 -3.41884)
			(size 0.3048 0.3048)
			(layers "F.Cu" "F.Mask" "F.Paste")
			(net "GND")
		)
		(pad "EA34" smd circle
			(at -6.050026 3.420364)
			(size 0.3048 0.3048)
			(layers "F.Cu" "F.Mask" "F.Paste")
			(net "GND")
		)
		(pad "EB1" smd oval
			(at -6.35 -3.938524)
			(size 0.254 0.3302)
			(layers "F.Cu" "F.Mask" "F.Paste")
			(net "GND")
		)
		(pad "EB35" smd oval
			(at -6.35 3.940048)
			(size 0.254 0.3302)
			(layers "F.Cu" "F.Mask" "F.Paste")
			(net "GND")
		)
		(pad "EC7" smd circle
			(at -6.397498 -2.12471)
			(size 0.381 0.381)
			(layers "F.Cu" "F.Mask" "F.Paste")
			(net "P5E_CPU0_P0_TX_BUF_DP<2>")
		)
		(pad "EC26" smd circle
			(at -6.397498 1.339342)
			(size 0.381 0.381)
			(layers "F.Cu" "F.Mask" "F.Paste")
			(net "P5E_CPU0_P0_RX_DP<2>")
		)
		(pad "ED2" smd circle
			(at -6.649974 -3.41884)
			(size 0.3048 0.3048)
			(layers "F.Cu" "F.Mask" "F.Paste")
			(net "P5E_CPU0_P0_RX_BUF_DN<2>")
		)
		(pad "ED34" smd circle
			(at -6.649974 3.420364)
			(size 0.3048 0.3048)
			(layers "F.Cu" "F.Mask" "F.Paste")
			(net "P5E_CPU0_P0_TX_C_DN<2>")
		)
		(pad "EE10" smd circle
			(at -6.797294 -1.431798)
			(size 0.381 0.381)
			(layers "F.Cu" "F.Mask" "F.Paste")
			(net "P5E_CPU0_P0_TX_BUF_DN<2>")
		)
		(pad "EE29" smd circle
			(at -6.797294 2.032254)
			(size 0.381 0.381)
			(layers "F.Cu" "F.Mask" "F.Paste")
			(net "P5E_CPU0_P0_RX_DN<2>")
		)
		(pad "EF1" smd oval
			(at -6.949948 -3.938524)
			(size 0.254 0.3302)
			(layers "F.Cu" "F.Mask" "F.Paste")
			(net "P5E_CPU0_P0_RX_BUF_DP<2>")
		)
		(pad "EF35" smd oval
			(at -6.949948 3.940048)
			(size 0.254 0.3302)
			(layers "F.Cu" "F.Mask" "F.Paste")
			(net "P5E_CPU0_P0_TX_C_DP<2>")
		)
		(pad "EG4" smd circle
			(at -7.197344 -2.817368)
			(size 0.381 0.381)
			(layers "F.Cu" "F.Mask" "F.Paste")
			(net "GND")
		)
		(pad "EG13" smd circle
			(at -7.197344 -0.79629)
			(size 0.3048 0.3048)
			(layers "F.Cu" "F.Mask" "F.Paste")
			(net "GND")
		)
		(pad "EG17" smd circle
			(at -7.197344 -0.296164)
			(size 0.3048 0.3048)
			(layers "F.Cu" "F.Mask" "F.Paste")
			(net "P0V9_CPU0_RT0_2A")
		)
		(pad "EG20" smd circle
			(at -7.197344 0.203708)
			(size 0.3048 0.3048)
			(layers "F.Cu" "F.Mask" "F.Paste")
			(net "P0V9_CPU0_RT0_2A")
		)
		(pad "EG22" smd circle
			(at -7.197344 0.703834)
			(size 0.3048 0.3048)
			(layers "F.Cu" "F.Mask" "F.Paste")
			(net "GND")
		)
		(pad "EG32" smd circle
			(at -7.197344 2.724912)
			(size 0.381 0.381)
			(layers "F.Cu" "F.Mask" "F.Paste")
			(net "GND")
		)
		(pad "EH2" smd circle
			(at -7.249922 -3.41884)
			(size 0.3048 0.3048)
			(layers "F.Cu" "F.Mask" "F.Paste")
			(net "GND")
		)
		(pad "EH34" smd circle
			(at -7.249922 3.420364)
			(size 0.3048 0.3048)
			(layers "F.Cu" "F.Mask" "F.Paste")
			(net "GND")
		)
		(pad "EJ1" smd oval
			(at -7.549896 -3.938524)
			(size 0.254 0.3302)
			(layers "F.Cu" "F.Mask" "F.Paste")
			(net "GND")
		)
		(pad "EJ35" smd oval
			(at -7.549896 3.940048)
			(size 0.254 0.3302)
			(layers "F.Cu" "F.Mask" "F.Paste")
			(net "GND")
		)
		(pad "EK7" smd circle
			(at -7.597394 -2.12471)
			(size 0.381 0.381)
			(layers "F.Cu" "F.Mask" "F.Paste")
			(net "P5E_CPU0_P0_TX_BUF_DP<1>")
		)
		(pad "EK26" smd circle
			(at -7.597394 1.339342)
			(size 0.381 0.381)
			(layers "F.Cu" "F.Mask" "F.Paste")
			(net "P5E_CPU0_P0_RX_DP<1>")
		)
		(pad "EL2" smd circle
			(at -7.850124 -3.41884)
			(size 0.3048 0.3048)
			(layers "F.Cu" "F.Mask" "F.Paste")
			(net "P5E_CPU0_P0_RX_BUF_DN<1>")
		)
		(pad "EL34" smd circle
			(at -7.850124 3.420364)
			(size 0.3048 0.3048)
			(layers "F.Cu" "F.Mask" "F.Paste")
			(net "P5E_CPU0_P0_TX_C_DP<1>")
		)
		(pad "EM10" smd circle
			(at -7.997444 -1.431798)
			(size 0.381 0.381)
			(layers "F.Cu" "F.Mask" "F.Paste")
			(net "P5E_CPU0_P0_TX_BUF_DN<1>")
		)
		(pad "EM29" smd circle
			(at -7.997444 2.032254)
			(size 0.381 0.381)
			(layers "F.Cu" "F.Mask" "F.Paste")
			(net "P5E_CPU0_P0_RX_DN<1>")
		)
		(pad "EN1" smd oval
			(at -8.150098 -3.938524)
			(size 0.254 0.3302)
			(layers "F.Cu" "F.Mask" "F.Paste")
			(net "P5E_CPU0_P0_RX_BUF_DP<1>")
		)
		(pad "EN35" smd oval
			(at -8.150098 3.940048)
			(size 0.254 0.3302)
			(layers "F.Cu" "F.Mask" "F.Paste")
			(net "P5E_CPU0_P0_TX_C_DN<1>")
		)
		(pad "EP4" smd circle
			(at -8.397494 -2.817368)
			(size 0.381 0.381)
			(layers "F.Cu" "F.Mask" "F.Paste")
			(net "GND")
		)
		(pad "EP13" smd circle
			(at -8.397494 -0.79629)
			(size 0.3048 0.3048)
			(layers "F.Cu" "F.Mask" "F.Paste")
			(net "GND")
		)
		(pad "EP17" smd circle
			(at -8.397494 -0.296164)
			(size 0.3048 0.3048)
			(layers "F.Cu" "F.Mask" "F.Paste")
			(net "P0V9_CPU0_RT0_2A")
		)
		(pad "EP20" smd circle
			(at -8.397494 0.203708)
			(size 0.3048 0.3048)
			(layers "F.Cu" "F.Mask" "F.Paste")
			(net "P0V9_CPU0_RT0_2A")
		)
		(pad "EP22" smd circle
			(at -8.397494 0.703834)
			(size 0.3048 0.3048)
			(layers "F.Cu" "F.Mask" "F.Paste")
			(net "GND")
		)
		(pad "EP32" smd circle
			(at -8.397494 2.724912)
			(size 0.381 0.381)
			(layers "F.Cu" "F.Mask" "F.Paste")
			(net "GND")
		)
		(pad "ER2" smd circle
			(at -8.450072 -3.41884)
			(size 0.3048 0.3048)
			(layers "F.Cu" "F.Mask" "F.Paste")
			(net "GND")
		)
		(pad "ER34" smd circle
			(at -8.450072 3.420364)
			(size 0.3048 0.3048)
			(layers "F.Cu" "F.Mask" "F.Paste")
			(net "GND")
		)
		(pad "ET1" smd oval
			(at -8.750046 -3.938524)
			(size 0.254 0.3302)
			(layers "F.Cu" "F.Mask" "F.Paste")
			(net "GND")
		)
		(pad "ET35" smd oval
			(at -8.750046 3.940048)
			(size 0.254 0.3302)
			(layers "F.Cu" "F.Mask" "F.Paste")
			(net "GND")
		)
		(pad "EU7" smd circle
			(at -8.79729 -2.12471)
			(size 0.381 0.381)
			(layers "F.Cu" "F.Mask" "F.Paste")
			(net "P5E_CPU0_P0_TX_BUF_DP<0>")
		)
		(pad "EU26" smd circle
			(at -8.79729 1.339342)
			(size 0.381 0.381)
			(layers "F.Cu" "F.Mask" "F.Paste")
			(net "P5E_CPU0_P0_RX_DP<0>")
		)
		(pad "EV2" smd circle
			(at -9.05002 -3.41884)
			(size 0.3048 0.3048)
			(layers "F.Cu" "F.Mask" "F.Paste")
			(net "P5E_CPU0_P0_RX_BUF_DN<0>")
		)
		(pad "EV34" smd circle
			(at -9.05002 3.420364)
			(size 0.3048 0.3048)
			(layers "F.Cu" "F.Mask" "F.Paste")
			(net "P5E_CPU0_P0_TX_C_DN<0>")
		)
		(pad "EW10" smd circle
			(at -9.19734 -1.431798)
			(size 0.381 0.381)
			(layers "F.Cu" "F.Mask" "F.Paste")
			(net "P5E_CPU0_P0_TX_BUF_DN<0>")
		)
		(pad "EW29" smd circle
			(at -9.19734 2.032254)
			(size 0.381 0.381)
			(layers "F.Cu" "F.Mask" "F.Paste")
			(net "P5E_CPU0_P0_RX_DN<0>")
		)
		(pad "EY1" smd oval
			(at -9.349994 -3.938524)
			(size 0.254 0.3302)
			(layers "F.Cu" "F.Mask" "F.Paste")
			(net "P5E_CPU0_P0_RX_BUF_DP<0>")
		)
		(pad "EY35" smd oval
			(at -9.349994 3.940048)
			(size 0.254 0.3302)
			(layers "F.Cu" "F.Mask" "F.Paste")
			(net "P5E_CPU0_P0_TX_C_DP<0>")
		)
		(pad "F2" smd circle
			(at 10.150094 -3.41884)
			(size 0.3048 0.3048)
			(layers "F.Cu" "F.Mask" "F.Paste")
			(net "RST_RT_CPU0_P0_PERST_N")
		)
		(pad "F34" smd circle
			(at 10.150094 3.420364)
			(size 0.3048 0.3048)
			(layers "F.Cu" "F.Mask" "F.Paste")
			(net "RT_CPU0_P0_ADDR1")
		)
		(pad "FA15" smd circle
			(at -9.59739 -0.738886)
			(size 0.381 0.381)
			(layers "F.Cu" "F.Mask" "F.Paste")
			(net "GND")
		)
		(pad "FA32" smd circle
			(at -9.59739 2.724912)
			(size 0.381 0.381)
			(layers "F.Cu" "F.Mask" "F.Paste")
			(net "GND")
		)
		(pad "FB2" smd circle
			(at -9.649968 -3.41884)
			(size 0.3048 0.3048)
			(layers "F.Cu" "F.Mask" "F.Paste")
			(net "GND")
		)
		(pad "FB34" smd circle
			(at -9.649968 3.420364)
			(size 0.3048 0.3048)
			(layers "F.Cu" "F.Mask" "F.Paste")
			(net "GND")
		)
		(pad "FC3" smd circle
			(at -9.846818 -2.888488)
			(size 0.3048 0.3048)
			(layers "F.Cu" "F.Mask" "F.Paste")
			(net "GND")
		)
		(pad "FC6" smd circle
			(at -9.846818 -2.288286)
			(size 0.3048 0.3048)
			(layers "F.Cu" "F.Mask" "F.Paste")
			(net "GND")
		)
		(pad "FC9" smd circle
			(at -9.846818 -1.688338)
			(size 0.3048 0.3048)
			(layers "F.Cu" "F.Mask" "F.Paste")
			(net "GND")
		)
		(pad "FC19" smd circle
			(at -9.846818 0.111506)
			(size 0.3048 0.3048)
			(layers "F.Cu" "F.Mask" "F.Paste")
			(net "GND")
		)
		(pad "FC23" smd circle
			(at -9.846818 0.711708)
			(size 0.3048 0.3048)
			(layers "F.Cu" "F.Mask" "F.Paste")
			(net "GND")
		)
		(pad "FC25" smd circle
			(at -9.846818 1.311656)
			(size 0.3048 0.3048)
			(layers "F.Cu" "F.Mask" "F.Paste")
			(net "GND")
		)
		(pad "FC28" smd circle
			(at -9.846818 1.911604)
			(size 0.3048 0.3048)
			(layers "F.Cu" "F.Mask" "F.Paste")
			(net "GND")
		)
		(pad "FD1" smd oval
			(at -9.949942 -3.938524)
			(size 0.254 0.3302)
			(layers "F.Cu" "F.Mask" "F.Paste")
			(net "GND")
		)
		(pad "FD35" smd oval
			(at -9.949942 3.940048)
			(size 0.254 0.3302)
			(layers "F.Cu" "F.Mask" "F.Paste")
			(net "GND")
		)
		(pad "FE2" smd circle
			(at -10.249916 -3.41884)
			(size 0.3048 0.3048)
			(layers "F.Cu" "F.Mask" "F.Paste")
			(net "NCF_CPU0_P0_GND")
		)
		(pad "FE34" smd circle
			(at -10.249916 3.420364)
			(size 0.3048 0.3048)
			(layers "F.Cu" "F.Mask" "F.Paste")
			(net "NCF_CPU0_P0_GND")
		)
		(pad "FF5" smd circle
			(at -10.366248 -2.588514)
			(size 0.3048 0.3048)
			(layers "F.Cu" "F.Mask" "F.Paste")
			(net "SMB_RT_CPU0_P0_ROM_MUX_1D_R_SCL")
		)
		(pad "FF8" smd circle
			(at -10.366248 -1.988312)
			(size 0.3048 0.3048)
			(layers "F.Cu" "F.Mask" "F.Paste")
			(net "JTAG_TEST_MODE_RT_CPU0_P0")
		)
		(pad "FF11" smd circle
			(at -10.366248 -1.388364)
			(size 0.3048 0.3048)
			(layers "F.Cu" "F.Mask" "F.Paste")
			(net "RST_RT_CPU0_P0_RESET_N")
		)
		(pad "FF14" smd circle
			(at -10.366248 -0.788416)
			(size 0.3048 0.3048)
			(layers "F.Cu" "F.Mask" "F.Paste")
			(net "GND")
		)
		(pad "FF18" smd circle
			(at -10.366248 -0.188468)
			(size 0.3048 0.3048)
			(layers "F.Cu" "F.Mask" "F.Paste")
			(net "CLK_100M_RETIMER_CPU0_P0_DN")
		)
		(pad "FF21" smd circle
			(at -10.366248 0.41148)
			(size 0.3048 0.3048)
			(layers "F.Cu" "F.Mask" "F.Paste")
			(net "GND")
		)
		(pad "FF24" smd circle
			(at -10.366248 1.011682)
			(size 0.3048 0.3048)
			(layers "F.Cu" "F.Mask" "F.Paste")
			(net "TEST0_RT_CPU0_P0")
		)
		(pad "FF27" smd circle
			(at -10.366248 1.61163)
			(size 0.3048 0.3048)
			(layers "F.Cu" "F.Mask" "F.Paste")
			(net "TEST1_RT_CPU0_P0")
		)
		(pad "FF30" smd circle
			(at -10.366248 2.211578)
			(size 0.3048 0.3048)
			(layers "F.Cu" "F.Mask" "F.Paste")
			(net "TEST2_RT_CPU0_P0")
		)
		(pad "FF33" smd circle
			(at -10.366248 2.811526)
			(size 0.3048 0.3048)
			(layers "F.Cu" "F.Mask" "F.Paste")
			(net "RT_CPU0_P0_SCAN_MODE")
		)
		(pad "FG1" smd oval
			(at -10.54989 -3.938524)
			(size 0.254 0.3302)
			(layers "F.Cu" "F.Mask" "F.Paste")
			(net "NCF_CPU0_P0_GND")
		)
		(pad "FG35" smd oval
			(at -10.54989 3.940048)
			(size 0.254 0.3302)
			(layers "F.Cu" "F.Mask" "F.Paste")
			(net "NCF_CPU0_P0_GND")
		)
		(pad "FH2" smd circle
			(at -10.850118 -3.41884)
			(size 0.3048 0.3048)
			(layers "F.Cu" "F.Mask" "F.Paste")
			(net "NCF_CPU0_P0_GND")
		)
		(pad "FH34" smd circle
			(at -10.850118 3.420364)
			(size 0.3048 0.3048)
			(layers "F.Cu" "F.Mask" "F.Paste")
			(net "NCF_CPU0_P0_GND")
		)
		(pad "FJ3" smd oval
			(at -10.885932 -2.888488 90)
			(size 0.254 0.3302)
			(layers "F.Cu" "F.Mask" "F.Paste")
			(net "SMB_RT_CPU0_P0_ROM_MUX_1D_R_SDA")
		)
		(pad "FJ6" smd oval
			(at -10.885932 -2.288286 90)
			(size 0.254 0.3302)
			(layers "F.Cu" "F.Mask" "F.Paste")
			(net "Net_2200")
		)
		(pad "FJ9" smd oval
			(at -10.885932 -1.688338 90)
			(size 0.254 0.3302)
			(layers "F.Cu" "F.Mask" "F.Paste")
			(net "MODE_RT_CPU0_P0")
		)
		(pad "FJ12" smd oval
			(at -10.885932 -1.08839 90)
			(size 0.254 0.3302)
			(layers "F.Cu" "F.Mask" "F.Paste")
			(net "GND")
		)
		(pad "FJ16" smd oval
			(at -10.885932 -0.488442 90)
			(size 0.254 0.3302)
			(layers "F.Cu" "F.Mask" "F.Paste")
			(net "CLK_100M_RETIMER_CPU0_P0_DP")
		)
		(pad "FJ19" smd oval
			(at -10.885932 0.111506 90)
			(size 0.254 0.3302)
			(layers "F.Cu" "F.Mask" "F.Paste")
			(net "GND")
		)
		(pad "FJ23" smd oval
			(at -10.885932 0.711708 90)
			(size 0.254 0.3302)
			(layers "F.Cu" "F.Mask" "F.Paste")
			(net "Net_2201")
		)
		(pad "FJ25" smd oval
			(at -10.885932 1.311656 90)
			(size 0.254 0.3302)
			(layers "F.Cu" "F.Mask" "F.Paste")
			(net "GPIO2_RT_CPU0_P0")
		)
		(pad "FJ28" smd oval
			(at -10.885932 1.911604 90)
			(size 0.254 0.3302)
			(layers "F.Cu" "F.Mask" "F.Paste")
			(net "GPIO3_RT_CPU0_P0")
		)
		(pad "FJ31" smd oval
			(at -10.885932 2.511552 90)
			(size 0.254 0.3302)
			(layers "F.Cu" "F.Mask" "F.Paste")
			(net "Net_50")
		)
		(pad "G1" smd oval
			(at 9.85012 -3.938524)
			(size 0.254 0.3302)
			(layers "F.Cu" "F.Mask" "F.Paste")
			(net "RT_CPU0_P0_VQPS")
		)
		(pad "G35" smd oval
			(at 9.85012 3.940048)
			(size 0.254 0.3302)
			(layers "F.Cu" "F.Mask" "F.Paste")
			(net "CLKREQ_RT_CPU0_P0_N")
		)
		(pad "H12" smd circle
			(at 9.846818 -1.08839)
			(size 0.3048 0.3048)
			(layers "F.Cu" "F.Mask" "F.Paste")
			(net "GND")
		)
		(pad "H16" smd circle
			(at 9.846818 -0.488442)
			(size 0.3048 0.3048)
			(layers "F.Cu" "F.Mask" "F.Paste")
			(net "GND")
		)
		(pad "H19" smd circle
			(at 9.846818 0.111506)
			(size 0.3048 0.3048)
			(layers "F.Cu" "F.Mask" "F.Paste")
			(net "GND")
		)
		(pad "H31" smd circle
			(at 9.846818 2.511552)
			(size 0.3048 0.3048)
			(layers "F.Cu" "F.Mask" "F.Paste")
			(net "GND")
		)
		(pad "J4" smd circle
			(at 9.602724 -2.817368)
			(size 0.381 0.381)
			(layers "F.Cu" "F.Mask" "F.Paste")
			(net "GND")
		)
		(pad "J22" smd circle
			(at 9.602724 0.703834)
			(size 0.3048 0.3048)
			(layers "F.Cu" "F.Mask" "F.Paste")
			(net "GND")
		)
		(pad "K2" smd circle
			(at 9.549892 -3.41884)
			(size 0.3048 0.3048)
			(layers "F.Cu" "F.Mask" "F.Paste")
			(net "GND")
		)
		(pad "K34" smd circle
			(at 9.549892 3.420364)
			(size 0.3048 0.3048)
			(layers "F.Cu" "F.Mask" "F.Paste")
			(net "GND")
		)
		(pad "L1" smd oval
			(at 9.249918 -3.938524)
			(size 0.254 0.3302)
			(layers "F.Cu" "F.Mask" "F.Paste")
			(net "GND")
		)
		(pad "L35" smd oval
			(at 9.249918 3.940048)
			(size 0.254 0.3302)
			(layers "F.Cu" "F.Mask" "F.Paste")
			(net "GND")
		)
		(pad "M7" smd circle
			(at 9.202674 -2.12471)
			(size 0.381 0.381)
			(layers "F.Cu" "F.Mask" "F.Paste")
			(net "P5E_CPU0_P0_TX_BUF_DP<15>")
		)
		(pad "M26" smd circle
			(at 9.202674 1.339342)
			(size 0.381 0.381)
			(layers "F.Cu" "F.Mask" "F.Paste")
			(net "P5E_CPU0_P0_RX_DP<15>")
		)
		(pad "N2" smd circle
			(at 8.949944 -3.41884)
			(size 0.3048 0.3048)
			(layers "F.Cu" "F.Mask" "F.Paste")
			(net "P5E_CPU0_P0_RX_BUF_DN<15>")
		)
		(pad "N34" smd circle
			(at 8.949944 3.420364)
			(size 0.3048 0.3048)
			(layers "F.Cu" "F.Mask" "F.Paste")
			(net "P5E_CPU0_P0_TX_C_DN<15>")
		)
	)
)
